# S9S_MB_2U (Grand Teton) — schematic netlist excerpt (pin names and nets, part order shuffled) for the footprints in the layout excerpt that follows; sources: Cadence DE-HDL packaged netlist, KiCad conversion of 03242023_DA0F0TMBIJ0_F0T_Motherboard_J_brd_V01_OCP.brd

J27  SCONN288_ADR50017P130CC  SCONN288_ADR50017-P130CC IO  pkg DDR288S_1-1VXB  page 108
  VIN_BULK0  = P12V_S3_AUX_CPU1_NVDIMM
  RFU0  = TP_CHF_CPU1_DIMM1_FRU_0
  VIN_MGMT  = P3V3_AUX
  HSCL  = I3C_SPD_DDREFGH_CPU1_LVC1_SCL_2
  HSDA  = I3C_SPD_DDREFGH_CPU1_LVC1_SDA
  VSS0  = GND
  DQ0_A  = M_F_CPU1_SA_DQ<0>
  VSS1  = GND
  DQ1_A  = M_F_CPU1_SA_DQ<1>
  VSS2  = GND
  DQS0_A_T  = M_F_CPU1_SA_DQS_DP<0>
  DQS0_A_C  = M_F_CPU1_SA_DQS_DN<0>
  VSS3  = GND
  DQ4_A  = M_F_CPU1_SA_DQ<4>
  VSS4  = GND
  DQ5_A  = M_F_CPU1_SA_DQ<5>
  VSS5  = GND
  DQ8_A  = M_F_CPU1_SA_DQ<8>
  VSS6  = GND
  DQ9_A  = M_F_CPU1_SA_DQ<9>
  VSS7  = GND
  DQS1_A_T  = M_F_CPU1_SA_DQS_DP<1>
  DQS1_A_C  = M_F_CPU1_SA_DQS_DN<1>
  VSS8  = GND
  DQ12_A  = M_F_CPU1_SA_DQ<12>
  VSS9  = GND
  DQ13_A  = M_F_CPU1_SA_DQ<13>
  VSS10  = GND
  DQ16_A  = M_F_CPU1_SA_DQ<16>
  VSS11  = GND
  DQ17_A  = M_F_CPU1_SA_DQ<17>
  VSS12  = GND
  DQS2_A_T  = M_F_CPU1_SA_DQS_DP<2>
  DQS2_A_C  = M_F_CPU1_SA_DQS_DN<2>
  VSS13  = GND
  DQ20_A  = M_F_CPU1_SA_DQ<20>
  VSS14  = GND
  DQ21_A  = M_F_CPU1_SA_DQ<21>
  VSS15  = GND
  DQ24_A  = M_F_CPU1_SA_DQ<24>
  VSS16  = GND
  DQ25_A  = M_F_CPU1_SA_DQ<25>
  VSS17  = GND
  DQS3_A_T  = M_F_CPU1_SA_DQS_DP<3>
  DQS3_A_C  = M_F_CPU1_SA_DQS_DN<3>
  VSS18  = GND
  DQ28_A  = M_F_CPU1_SA_DQ<28>
  VSS19  = GND
  DQ29_A  = M_F_CPU1_SA_DQ<29>
  VSS20  = GND
  CB0_A  = M_F_CPU1_SA_CB<0>
  VSS21  = GND
  CB1_A  = M_F_CPU1_SA_CB<1>
  VSS22  = GND
  DQS4_A_T  = M_F_CPU1_SA_DQS_DP<4>
  DQS4_A_C  = M_F_CPU1_SA_DQS_DN<4>
  VSS23  = GND
  CB4_A  = M_F_CPU1_SA_CB<4>
  VSS24  = GND
  CB5_A  = M_F_CPU1_SA_CB<5>
  VSS25  = GND
  ALERT_N  = M_F_CPU1_ALERT_N
  VSS26  = GND
  CS0_A_N  = M_F_CPU1_SA_CS_N<0>
  VSS27  = GND
  CA0_A  = M_F_CPU1_SA_CA<0>
  VSS28  = GND
  CA2_A  = M_F_CPU1_SA_CA<2>
  VSS29  = GND
  CA4_A  = M_F_CPU1_SA_CA<4>
  VSS30  = GND
  CA6_A  = M_F_CPU1_SA_CA<6>
  VSS31  = GND
  PAR_A  = M_F_CPU1_SA_PAR
  VSS32  = GND
  CA0_B  = M_F_CPU1_SB_CA<0>
  VSS33  = GND
  CA2_B  = M_F_CPU1_SB_CA<2>
  VSS34  = GND
  CA4_B  = M_F_CPU1_SB_CA<4>
  VSS35  = GND
  CA6_B  = M_F_CPU1_SB_CA<6>
  VSS36  = GND
  CS0_B_N  = M_F_CPU1_SB_CS_N<0>
  VSS37  = GND
  \lbd||rsp_a_n\  = M_F_CPU1_SA_RSP<0>
  \lbs||rsp_b_n\  = M_F_CPU1_SB_RSP<0>
  VSS38  = GND
  CB4_B  = M_F_CPU1_SB_CB<4>
  VSS39  = GND
  CB5_B  = M_F_CPU1_SB_CB<5>
  VSS40  = GND
  \dqs9_b_t||tdqs9_b_t||dbi4_b_n\  = M_F_CPU1_SB_DQS_DP<9>
  \dqs9_b_c||tdqs9_b_c\  = M_F_CPU1_SB_DQS_DN<9>
  VSS41  = GND
  CB0_B  = M_F_CPU1_SB_CB<0>
  VSS42  = GND
  CB1_B  = M_F_CPU1_SB_CB<1>
  VSS43  = GND
  DQ0_B  = M_F_CPU1_SB_DQ<0>
  VSS44  = GND
  DQ1_B  = M_F_CPU1_SB_DQ<1>
  VSS45  = GND
  DQS0_B_T  = M_F_CPU1_SB_DQS_DP<0>
  DQS0_B_C  = M_F_CPU1_SB_DQS_DN<0>
  VSS46  = GND
  DQ4_B  = M_F_CPU1_SB_DQ<4>
  VSS47  = GND
  DQ5_B  = M_F_CPU1_SB_DQ<5>
  VSS48  = GND
  DQ8_B  = M_F_CPU1_SB_DQ<8>
  VSS49  = GND
  DQ9_B  = M_F_CPU1_SB_DQ<9>
  VSS50  = GND
  DQS1_B_T  = M_F_CPU1_SB_DQS_DP<1>
  DQS1_B_C  = M_F_CPU1_SB_DQS_DN<1>
  VSS51  = GND
  DQ12_B  = M_F_CPU1_SB_DQ<12>
  VSS52  = GND
  DQ13_B  = M_F_CPU1_SB_DQ<13>
  VSS53  = GND
  DQ16_B  = M_F_CPU1_SB_DQ<16>
  VSS54  = GND
  DQ17_B  = M_F_CPU1_SB_DQ<17>
  VSS55  = GND
  DQS2_B_T  = M_F_CPU1_SB_DQS_DP<2>
  DQS2_B_C  = M_F_CPU1_SB_DQS_DN<2>
  VSS56  = GND
  DQ20_B  = M_F_CPU1_SB_DQ<20>
  VSS57  = GND
  DQ21_B  = M_F_CPU1_SB_DQ<21>
  VSS58  = GND
  DQ24_B  = M_F_CPU1_SB_DQ<24>
  VSS59  = GND
  DQ25_B  = M_F_CPU1_SB_DQ<25>
  VSS60  = GND
  DQS3_B_T  = M_F_CPU1_SB_DQS_DP<3>
  DQS3_B_C  = M_F_CPU1_SB_DQS_DN<3>
  VSS61  = GND
  DQ28_B  = M_F_CPU1_SB_DQ<28>
  VSS62  = GND
  DQ29_B  = M_F_CPU1_SB_DQ<29>
  VSS63  = GND
  RFU1  = TP_CHF_CPU1_DIMM1_FRU_1
  VIN_BULK1  = P12V_S3_AUX_CPU1_NVDIMM
  VIN_BULK2  = P12V_S3_AUX_CPU1_NVDIMM
  \pwr_good||fail_n\  = PWRGD_CHF_CPU1_DIMM1
  HSA  = PD_CHF_CPU1_DIMM1_SAA
  RFU2  = TP_CHF_CPU1_DIMM1_FRU_2
  RFU3  = TP_CHF_CPU1_DIMM1_FRU_3
  VSS64  = GND
  DQ2_A  = M_F_CPU1_SA_DQ<2>
  VSS65  = GND
  DQ3_A  = M_F_CPU1_SA_DQ<3>
  VSS66  = GND
  \dqs5_a_c||tdqs5_a_c||dqs5_a_t||tdqs5_a_t\  = M_F_CPU1_SA_DQS_DN<5>
  \dqs5_a_t||tdqs5_a_t\  = M_F_CPU1_SA_DQS_DP<5>
  VSS67  = GND
  DQ6_A  = M_F_CPU1_SA_DQ<6>
  VSS68  = GND
  DQ7_A  = M_F_CPU1_SA_DQ<7>
  VSS69  = GND
  DQ10_A  = M_F_CPU1_SA_DQ<10>
  VSS70  = GND
  DQ11_A  = M_F_CPU1_SA_DQ<11>
  VSS71  = GND
  \dqs6_a_c||tdqs6_a_c||dqs6_a_t||tdqs6_a_t\  = M_F_CPU1_SA_DQS_DN<6>
  \dqs6_a_t||tdqs6_a_t\  = M_F_CPU1_SA_DQS_DP<6>
  VSS72  = GND
  DQ14_A  = M_F_CPU1_SA_DQ<14>
  VSS73  = GND
  DQ15_A  = M_F_CPU1_SA_DQ<15>
  VSS74  = GND
  DQ18_A  = M_F_CPU1_SA_DQ<18>
  VSS75  = GND
  DQ19_A  = M_F_CPU1_SA_DQ<19>
  VSS76  = GND
  \dqs7_a_c||tdqs7_a_c\  = M_F_CPU1_SA_DQS_DN<7>
  \dqs7_a_t||tdqs7_a_t\  = M_F_CPU1_SA_DQS_DP<7>
  VSS77  = GND
  DQ22_A  = M_F_CPU1_SA_DQ<22>
  VSS78  = GND
  DQ23_A  = M_F_CPU1_SA_DQ<23>
  VSS79  = GND
  DQ26_A  = M_F_CPU1_SA_DQ<26>
  VSS80  = GND
  DQ27_A  = M_F_CPU1_SA_DQ<27>
  VSS81  = GND
  \dqs8_a_c||tdqs8_a_c\  = M_F_CPU1_SA_DQS_DN<8>
  \dqs8_a_t||tdqs8_a_t\  = M_F_CPU1_SA_DQS_DP<8>
  VSS82  = GND
  DQ30_A  = M_F_CPU1_SA_DQ<30>
  VSS83  = GND
  DQ31_A  = M_F_CPU1_SA_DQ<31>
  VSS84  = GND
  CB2_A  = M_F_CPU1_SA_CB<2>
  VSS85  = GND
  CB3_A  = M_F_CPU1_SA_CB<3>
  VSS86  = GND
  \dqs9_a_c||tdqs9_a_c\  = M_F_CPU1_SA_DQS_DN<9>
  \dqs9_a_t||tdqs9_a_t\  = M_F_CPU1_SA_DQS_DP<9>
  VSS87  = GND
  CB6_A  = M_F_CPU1_SA_CB<6>
  VSS88  = GND
  CB7_A  = M_F_CPU1_SA_CB<7>
  VSS89  = GND
  RESET_N  = RST_M_EF_CPU1_FPGA_N
  VSS90  = GND
  CS1_A_N  = M_F_CPU1_SA_CS_N<1>
  VSS91  = GND
  CA1_A  = M_F_CPU1_SA_CA<1>
  VSS92  = GND
  CA3_A  = M_F_CPU1_SA_CA<3>
  VSS93  = GND
  CA5_A  = M_F_CPU1_SA_CA<5>
  VSS94  = GND
  CK_T  = M_F_CPU1_CLK_DP<0>
  CK_C  = M_F_CPU1_CLK_DN<0>
  VSS95  = GND
  RFU4  = TP_CHF_CPU1_DIMM1_FRU_4
  CA1_B  = M_F_CPU1_SB_CA<1>
  VSS96  = GND
  CA3_B  = M_F_CPU1_SB_CA<3>
  VSS97  = GND
  CA5_B  = M_F_CPU1_SB_CA<5>
  VSS98  = GND
  PAR_B  = M_F_CPU1_SB_PAR
  VSS99  = GND
  CS1_B_N  = M_F_CPU1_SB_CS_N<1>
  VSS100  = GND
  RFU5  = TP_CHF_CPU1_DIMM1_FRU_5
  RFU6  = TP_CHF_CPU1_DIMM1_FRU_6
  VSS101  = GND
  CB6_B  = M_F_CPU1_SB_CB<6>
  VSS102  = GND
  CB7_B  = M_F_CPU1_SB_CB<7>
  VSS103  = GND
  DQS4_B_C  = M_F_CPU1_SB_DQS_DN<4>
  DQS4_B_T  = M_F_CPU1_SB_DQS_DP<4>
  VSS104  = GND
  CB2_B  = M_F_CPU1_SB_CB<2>
  VSS105  = GND
  CB3_B  = M_F_CPU1_SB_CB<3>
  VSS106  = GND
  DQ2_B  = M_F_CPU1_SB_DQ<2>
  VSS107  = GND
  DQ3_B  = M_F_CPU1_SB_DQ<3>
  VSS108  = GND
  \dqs5_b_c||tdqs5_b_c\  = M_F_CPU1_SB_DQS_DN<5>
  \dqs5_b_t||tdqs5_b_t\  = M_F_CPU1_SB_DQS_DP<5>
  VSS109  = GND
  DQ6_B  = M_F_CPU1_SB_DQ<6>
  VSS110  = GND
  DQ7_B  = M_F_CPU1_SB_DQ<7>
  VSS111  = GND
  DQ10_B  = M_F_CPU1_SB_DQ<10>
  VSS112  = GND
  DQ11_B  = M_F_CPU1_SB_DQ<11>
  VSS113  = GND
  \dqs6_b_c||tdqs6_b_c\  = M_F_CPU1_SB_DQS_DN<6>
  \dqs6_b_t||tdqs6_b_t\  = M_F_CPU1_SB_DQS_DP<6>
  VSS114  = GND
  DQ14_B  = M_F_CPU1_SB_DQ<14>
  VSS115  = GND
  DQ15_B  = M_F_CPU1_SB_DQ<15>
  VSS116  = GND
  DQ18_B  = M_F_CPU1_SB_DQ<18>
  VSS117  = GND
  DQ19_B  = M_F_CPU1_SB_DQ<19>
  VSS118  = GND
  \dqs7_b_c||tdqs7_b_c\  = M_F_CPU1_SB_DQS_DN<7>
  \dqs7_b_t||tdqs7_b_t\  = M_F_CPU1_SB_DQS_DP<7>
  VSS119  = GND
  DQ22_B  = M_F_CPU1_SB_DQ<22>
  VSS120  = GND
  DQ23_B  = M_F_CPU1_SB_DQ<23>
  VSS121  = GND
  DQ26_B  = M_F_CPU1_SB_DQ<26>
  VSS122  = GND
  DQ27_B  = M_F_CPU1_SB_DQ<27>
  VSS123  = GND
  \dqs8_b_c||tdqs8_b_c\  = M_F_CPU1_SB_DQS_DN<8>
  \dqs8_b_t||tdqs8_b_t\  = M_F_CPU1_SB_DQS_DP<8>
  VSS124  = GND
  DQ30_B  = M_F_CPU1_SB_DQ<30>
  VSS125  = GND
  DQ31_B  = M_F_CPU1_SB_DQ<31>
  VSS126  = GND
  G1  = GND
  G2  = GND
  G3  = GND

(kicad_pcb
	(version 20260206)
	(generator "pcbnew")
	(generator_version "10.0")
	(general
		(thickness 1.6)
		(legacy_teardrops no)
	)
	(paper "A4")
	(title_block
		(title "03242023_DA0F0TMBIJ0_F0T_Motherboard_J_brd_V01_OCP.brd")
		(comment 1 "Grand Teton / footprint 1301 of 6105 (J27), pads 138-182 of 291")
	)
	(layers
		(0 "F.Cu" signal "TOP")
		(4 "In1.Cu" signal "GND")
		(6 "In2.Cu" signal "IN1")
		(8 "In3.Cu" signal "GND1")
		(10 "In4.Cu" signal "IN2")
		(12 "In5.Cu" signal "GND2")
		(14 "In6.Cu" signal "IN3")
		(16 "In7.Cu" signal "GND3")
		(18 "In8.Cu" signal "VCC")
		(20 "In9.Cu" signal "VCC1")
		(22 "In10.Cu" signal "GND4")
		(24 "In11.Cu" signal "IN4")
		(26 "In12.Cu" signal "GND5")
		(28 "In13.Cu" signal "IN5")
		(30 "In14.Cu" signal "GND6")
		(32 "In15.Cu" signal "IN6")
		(34 "In16.Cu" signal "GND7")
		(2 "B.Cu" signal "BOTTOM")
		(9 "F.Adhes" user "F.Adhesive")
		(11 "B.Adhes" user "B.Adhesive")
		(13 "F.Paste" user "Package Geometry/Pastemask Top")
		(15 "B.Paste" user "Package Geometry/Pastemask Bottom")
		(5 "F.SilkS" user "Ref Des/Silkscreen Top")
		(7 "B.SilkS" user "Ref Des/Silkscreen Bottom")
		(1 "F.Mask" user "Board Geometry/Soldermask Top")
		(3 "B.Mask" user "Board Geometry/Soldermask Bottom")
		(17 "Dwgs.User" user "User.Drawings")
		(19 "Cmts.User" user "User.Comments")
		(21 "Eco1.User" user "User.Eco1")
		(23 "Eco2.User" user "User.Eco2")
		(25 "Edge.Cuts" user "Board Geometry/Outline")
		(27 "Margin" user)
		(31 "F.CrtYd" user "Package Geometry/Place Bound Top")
		(29 "B.CrtYd" user "Package Geometry/Place Bound Bottom")
		(35 "F.Fab" user "Ref Des/Assembly Top")
		(33 "B.Fab" user "Ref Des/Assembly Bottom")
	)
	(footprint ""
		(layer "F.Cu")
		(at 183.49468 -258.091686)
		(property "Reference" "J27"
			(at 2.19456 -81.755488 0)
			(unlocked yes)
			(layer "F.SilkS")
			(effects
				(font
					(size 0.7874 0.5842)
					(thickness 0.1524)
				)
				(justify left)
			)
		)
		(property "Value" ""
			(at 0 0 0)
			(layer "F.Fab")
			(effects
				(font
					(size 1.27 1.27)
				)
			)
		)
		(duplicate_pad_numbers_are_jumpers no)
		(pad "138" smd rect
			(at -2.050034 58.224928 270)
			(size 0.519938 1.4986)
			(layers "F.Cu" "F.Mask" "F.Paste")
			(net "M_F_CPU1_SB_DQS_DN<3>")
		)
		(pad "139" smd rect
			(at -2.050034 59.075066 270)
			(size 0.519938 1.4986)
			(layers "F.Cu" "F.Mask" "F.Paste")
			(net "GND")
		)
		(pad "140" smd rect
			(at -2.050034 59.92495 270)
			(size 0.519938 1.4986)
			(layers "F.Cu" "F.Mask" "F.Paste")
			(net "M_F_CPU1_SB_DQ<28>")
		)
		(pad "141" smd rect
			(at -2.050034 60.775088 270)
			(size 0.519938 1.4986)
			(layers "F.Cu" "F.Mask" "F.Paste")
			(net "GND")
		)
		(pad "142" smd rect
			(at -2.050034 61.624972 270)
			(size 0.519938 1.4986)
			(layers "F.Cu" "F.Mask" "F.Paste")
			(net "M_F_CPU1_SB_DQ<29>")
		)
		(pad "143" smd rect
			(at -2.050034 62.47511 270)
			(size 0.519938 1.4986)
			(layers "F.Cu" "F.Mask" "F.Paste")
			(net "GND")
		)
		(pad "144" smd rect
			(at -2.050034 63.324994 270)
			(size 0.519938 1.4986)
			(layers "F.Cu" "F.Mask" "F.Paste")
			(net "TP_CHF_CPU1_DIMM1_FRU_1")
		)
		(pad "145" smd rect
			(at 2.050034 -63.324994 270)
			(size 0.519938 1.4986)
			(layers "F.Cu" "F.Mask" "F.Paste")
			(net "P12V_S3_AUX_CPU1_NVDIMM")
		)
		(pad "146" smd rect
			(at 2.050034 -62.47511 270)
			(size 0.519938 1.4986)
			(layers "F.Cu" "F.Mask" "F.Paste")
			(net "P12V_S3_AUX_CPU1_NVDIMM")
		)
		(pad "147" smd rect
			(at 2.050034 -61.624972 270)
			(size 0.519938 1.4986)
			(layers "F.Cu" "F.Mask" "F.Paste")
			(net "PWRGD_CHF_CPU1_DIMM1")
		)
		(pad "148" smd rect
			(at 2.050034 -60.775088 270)
			(size 0.519938 1.4986)
			(layers "F.Cu" "F.Mask" "F.Paste")
			(net "PD_CHF_CPU1_DIMM1_SAA")
		)
		(pad "149" smd rect
			(at 2.050034 -59.92495 270)
			(size 0.519938 1.4986)
			(layers "F.Cu" "F.Mask" "F.Paste")
			(net "TP_CHF_CPU1_DIMM1_FRU_2")
		)
		(pad "150" smd rect
			(at 2.050034 -59.075066 270)
			(size 0.519938 1.4986)
			(layers "F.Cu" "F.Mask" "F.Paste")
			(net "TP_CHF_CPU1_DIMM1_FRU_3")
		)
		(pad "151" smd rect
			(at 2.050034 -58.224928 270)
			(size 0.519938 1.4986)
			(layers "F.Cu" "F.Mask" "F.Paste")
			(net "GND")
		)
		(pad "152" smd rect
			(at 2.050034 -57.375044 270)
			(size 0.519938 1.4986)
			(layers "F.Cu" "F.Mask" "F.Paste")
			(net "M_F_CPU1_SA_DQ<2>")
		)
		(pad "153" smd rect
			(at 2.050034 -56.524906 270)
			(size 0.519938 1.4986)
			(layers "F.Cu" "F.Mask" "F.Paste")
			(net "GND")
		)
		(pad "154" smd rect
			(at 2.050034 -55.675022 270)
			(size 0.519938 1.4986)
			(layers "F.Cu" "F.Mask" "F.Paste")
			(net "M_F_CPU1_SA_DQ<3>")
		)
		(pad "155" smd rect
			(at 2.050034 -54.824884 270)
			(size 0.519938 1.4986)
			(layers "F.Cu" "F.Mask" "F.Paste")
			(net "GND")
		)
		(pad "156" smd rect
			(at 2.050034 -53.975 270)
			(size 0.519938 1.4986)
			(layers "F.Cu" "F.Mask" "F.Paste")
			(net "M_F_CPU1_SA_DQS_DN<5>")
		)
		(pad "157" smd rect
			(at 2.050034 -53.125116 270)
			(size 0.519938 1.4986)
			(layers "F.Cu" "F.Mask" "F.Paste")
			(net "M_F_CPU1_SA_DQS_DP<5>")
		)
		(pad "158" smd rect
			(at 2.050034 -52.274978 270)
			(size 0.519938 1.4986)
			(layers "F.Cu" "F.Mask" "F.Paste")
			(net "GND")
		)
		(pad "159" smd rect
			(at 2.050034 -51.425094 270)
			(size 0.519938 1.4986)
			(layers "F.Cu" "F.Mask" "F.Paste")
			(net "M_F_CPU1_SA_DQ<6>")
		)
		(pad "160" smd rect
			(at 2.050034 -50.574956 270)
			(size 0.519938 1.4986)
			(layers "F.Cu" "F.Mask" "F.Paste")
			(net "GND")
		)
		(pad "161" smd rect
			(at 2.050034 -49.725072 270)
			(size 0.519938 1.4986)
			(layers "F.Cu" "F.Mask" "F.Paste")
			(net "M_F_CPU1_SA_DQ<7>")
		)
		(pad "162" smd rect
			(at 2.050034 -48.874934 270)
			(size 0.519938 1.4986)
			(layers "F.Cu" "F.Mask" "F.Paste")
			(net "GND")
		)
		(pad "163" smd rect
			(at 2.050034 -48.02505 270)
			(size 0.519938 1.4986)
			(layers "F.Cu" "F.Mask" "F.Paste")
			(net "M_F_CPU1_SA_DQ<10>")
		)
		(pad "164" smd rect
			(at 2.050034 -47.174912 270)
			(size 0.519938 1.4986)
			(layers "F.Cu" "F.Mask" "F.Paste")
			(net "GND")
		)
		(pad "165" smd rect
			(at 2.050034 -46.325028 270)
			(size 0.519938 1.4986)
			(layers "F.Cu" "F.Mask" "F.Paste")
			(net "M_F_CPU1_SA_DQ<11>")
		)
		(pad "166" smd rect
			(at 2.050034 -45.47489 270)
			(size 0.519938 1.4986)
			(layers "F.Cu" "F.Mask" "F.Paste")
			(net "GND")
		)
		(pad "167" smd rect
			(at 2.050034 -44.625006 270)
			(size 0.519938 1.4986)
			(layers "F.Cu" "F.Mask" "F.Paste")
			(net "M_F_CPU1_SA_DQS_DN<6>")
		)
		(pad "168" smd rect
			(at 2.050034 -43.775122 270)
			(size 0.519938 1.4986)
			(layers "F.Cu" "F.Mask" "F.Paste")
			(net "M_F_CPU1_SA_DQS_DP<6>")
		)
		(pad "169" smd rect
			(at 2.050034 -42.924984 270)
			(size 0.519938 1.4986)
			(layers "F.Cu" "F.Mask" "F.Paste")
			(net "GND")
		)
		(pad "170" smd rect
			(at 2.050034 -42.0751 270)
			(size 0.519938 1.4986)
			(layers "F.Cu" "F.Mask" "F.Paste")
			(net "M_F_CPU1_SA_DQ<14>")
		)
		(pad "171" smd rect
			(at 2.050034 -41.224962 270)
			(size 0.519938 1.4986)
			(layers "F.Cu" "F.Mask" "F.Paste")
			(net "GND")
		)
		(pad "172" smd rect
			(at 2.050034 -40.375078 270)
			(size 0.519938 1.4986)
			(layers "F.Cu" "F.Mask" "F.Paste")
			(net "M_F_CPU1_SA_DQ<15>")
		)
		(pad "173" smd rect
			(at 2.050034 -39.52494 270)
			(size 0.519938 1.4986)
			(layers "F.Cu" "F.Mask" "F.Paste")
			(net "GND")
		)
		(pad "174" smd rect
			(at 2.050034 -38.675056 270)
			(size 0.519938 1.4986)
			(layers "F.Cu" "F.Mask" "F.Paste")
			(net "M_F_CPU1_SA_DQ<18>")
		)
		(pad "175" smd rect
			(at 2.050034 -37.824918 270)
			(size 0.519938 1.4986)
			(layers "F.Cu" "F.Mask" "F.Paste")
			(net "GND")
		)
		(pad "176" smd rect
			(at 2.050034 -36.975034 270)
			(size 0.519938 1.4986)
			(layers "F.Cu" "F.Mask" "F.Paste")
			(net "M_F_CPU1_SA_DQ<19>")
		)
		(pad "177" smd rect
			(at 2.050034 -36.124896 270)
			(size 0.519938 1.4986)
			(layers "F.Cu" "F.Mask" "F.Paste")
			(net "GND")
		)
		(pad "178" smd rect
			(at 2.050034 -35.275012 270)
			(size 0.519938 1.4986)
			(layers "F.Cu" "F.Mask" "F.Paste")
			(net "M_F_CPU1_SA_DQS_DN<7>")
		)
		(pad "179" smd rect
			(at 2.050034 -34.425128 270)
			(size 0.519938 1.4986)
			(layers "F.Cu" "F.Mask" "F.Paste")
			(net "M_F_CPU1_SA_DQS_DP<7>")
		)
		(pad "180" smd rect
			(at 2.050034 -33.57499 270)
			(size 0.519938 1.4986)
			(layers "F.Cu" "F.Mask" "F.Paste")
			(net "GND")
		)
		(pad "181" smd rect
			(at 2.050034 -32.725106 270)
			(size 0.519938 1.4986)
			(layers "F.Cu" "F.Mask" "F.Paste")
			(net "M_F_CPU1_SA_DQ<22>")
		)
		(pad "182" smd rect
			(at 2.050034 -31.874968 270)
			(size 0.519938 1.4986)
			(layers "F.Cu" "F.Mask" "F.Paste")
			(net "GND")
		)
	)
)
